# T6G (Grand Teton) — schematic netlist excerpt (pin names and nets, part order shuffled) for the footprints in the layout excerpt that follows; sources: Cadence DE-HDL packaged netlist, KiCad conversion of 04192023_DAF0TMB3IC0_F0TG_MB_C_brd_V02_OCP.brd

C5004  Q_CAP  1000PF 50V 5% X7R  pkg 0402  page 200 : A = GND ; B = PWRGD_PVDDCR_CPU1_P0

PQ11  MOSFET_PCH_GDS_ESD_PROTECTED  PJA3415AE IC  pkg SOT23_GDSXC  page 210
  D  = PVDDCR_SOC_P1_EN//ADDR_CFG
  G  = PVDDCR_SOC_P1_EN_GD
  S  = P3V3_AUX

(kicad_pcb
	(version 20260206)
	(generator "pcbnew")
	(generator_version "10.0")
	(general
		(thickness 1.6)
		(legacy_teardrops no)
	)
	(paper "A4")
	(title_block
		(title "04192023_DAF0TMB3IC0_F0TG_MB_C_brd_V02_OCP.brd")
		(comment 1 "Grand Teton / footprints 1043-1044 of 8354")
	)
	(layers
		(0 "F.Cu" signal "TOP")
		(4 "In1.Cu" signal "GND")
		(6 "In2.Cu" signal "IN1")
		(8 "In3.Cu" signal "GND1")
		(10 "In4.Cu" signal "IN2")
		(12 "In5.Cu" signal "GND2")
		(14 "In6.Cu" signal "IN3")
		(16 "In7.Cu" signal "GND3")
		(18 "In8.Cu" signal "VCC")
		(20 "In9.Cu" signal "VCC1")
		(22 "In10.Cu" signal "GND4")
		(24 "In11.Cu" signal "IN4")
		(26 "In12.Cu" signal "GND5")
		(28 "In13.Cu" signal "IN5")
		(30 "In14.Cu" signal "GND6")
		(32 "In15.Cu" signal "IN6")
		(34 "In16.Cu" signal "GND7")
		(2 "B.Cu" signal "BOTTOM")
		(9 "F.Adhes" user "F.Adhesive")
		(11 "B.Adhes" user "B.Adhesive")
		(13 "F.Paste" user "Package Geometry/Pastemask Top")
		(15 "B.Paste" user "Package Geometry/Pastemask Bottom")
		(5 "F.SilkS" user "Ref Des/Silkscreen Top")
		(7 "B.SilkS" user "Ref Des/Silkscreen Bottom")
		(1 "F.Mask" user "Board Geometry/Soldermask Top")
		(3 "B.Mask" user "Board Geometry/Soldermask Bottom")
		(17 "Dwgs.User" user "User.Drawings")
		(19 "Cmts.User" user "User.Comments")
		(21 "Eco1.User" user "User.Eco1")
		(23 "Eco2.User" user "User.Eco2")
		(25 "Edge.Cuts" user "Board Geometry/Outline")
		(27 "Margin" user)
		(31 "F.CrtYd" user "Package Geometry/Place Bound Top")
		(29 "B.CrtYd" user "Package Geometry/Place Bound Bottom")
		(35 "F.Fab" user "Ref Des/Assembly Top")
		(33 "B.Fab" user "Ref Des/Assembly Bottom")
	)
	(footprint ""
		(layer "F.Cu")
		(at 107.256834 -136.306052 90)
		(property "Reference" "PQ11"
			(at -1.27 2.31267 90)
			(unlocked yes)
			(layer "F.SilkS")
			(effects
				(font
					(size 0.7874 0.5842)
					(thickness 0.1524)
				)
				(justify left)
			)
		)
		(property "Value" ""
			(at 0 0 90)
			(layer "F.Fab")
			(effects
				(font
					(size 1.27 1.27)
				)
			)
		)
		(duplicate_pad_numbers_are_jumpers no)
		(fp_line
			(start 1.603248 -1.500124)
			(end 1.603248 1.500124)
			(stroke
				(width 0.1524)
				(type default)
			)
			(layer "F.SilkS")
		)
		(fp_line
			(start -1.603248 -1.500124)
			(end 1.603248 -1.500124)
			(stroke
				(width 0.1524)
				(type default)
			)
			(layer "F.SilkS")
		)
		(fp_line
			(start 1.603248 1.500124)
			(end -1.603248 1.500124)
			(stroke
				(width 0.1524)
				(type default)
			)
			(layer "F.SilkS")
		)
		(fp_line
			(start -1.603248 1.500124)
			(end -1.603248 -1.500124)
			(stroke
				(width 0.1524)
				(type default)
			)
			(layer "F.SilkS")
		)
		(fp_line
			(start 0.700024 -1.500124)
			(end -0.700024 -1.500124)
			(stroke
				(width 0.1)
				(type default)
			)
			(layer "F.Fab")
		)
		(fp_line
			(start -0.700024 -1.500124)
			(end -0.700024 -1.169924)
			(stroke
				(width 0.1)
				(type default)
			)
			(layer "F.Fab")
		)
		(fp_line
			(start -0.700024 -1.169924)
			(end -1.249934 -1.169924)
			(stroke
				(width 0.1)
				(type default)
			)
			(layer "F.Fab")
		)
		(fp_line
			(start -1.249934 -1.169924)
			(end -1.249934 -0.729996)
			(stroke
				(width 0.1)
				(type default)
			)
			(layer "F.Fab")
		)
		(fp_line
			(start -0.6985 -0.729996)
			(end -0.6985 0.729996)
			(stroke
				(width 0.1)
				(type default)
			)
			(layer "F.Fab")
		)
		(fp_line
			(start -1.249934 -0.729996)
			(end -0.6985 -0.729996)
			(stroke
				(width 0.1)
				(type default)
			)
			(layer "F.Fab")
		)
		(fp_line
			(start 1.249934 -0.219964)
			(end 0.700024 -0.219964)
			(stroke
				(width 0.1)
				(type default)
			)
			(layer "F.Fab")
		)
		(fp_line
			(start 0.700024 -0.219964)
			(end 0.700024 -1.500124)
			(stroke
				(width 0.1)
				(type default)
			)
			(layer "F.Fab")
		)
		(fp_line
			(start 1.249934 0.219964)
			(end 1.249934 -0.219964)
			(stroke
				(width 0.1)
				(type default)
			)
			(layer "F.Fab")
		)
		(fp_line
			(start 0.700024 0.219964)
			(end 1.249934 0.219964)
			(stroke
				(width 0.1)
				(type default)
			)
			(layer "F.Fab")
		)
		(fp_line
			(start -0.6985 0.729996)
			(end -1.249934 0.729996)
			(stroke
				(width 0.1)
				(type default)
			)
			(layer "F.Fab")
		)
		(fp_line
			(start -1.249934 0.729996)
			(end -1.249934 1.169924)
			(stroke
				(width 0.1)
				(type default)
			)
			(layer "F.Fab")
		)
		(fp_line
			(start -0.700024 1.169924)
			(end -0.700024 1.500124)
			(stroke
				(width 0.1)
				(type default)
			)
			(layer "F.Fab")
		)
		(fp_line
			(start -1.249934 1.169924)
			(end -0.700024 1.169924)
			(stroke
				(width 0.1)
				(type default)
			)
			(layer "F.Fab")
		)
		(fp_line
			(start 0.700024 1.500124)
			(end 0.700024 0.219964)
			(stroke
				(width 0.1)
				(type default)
			)
			(layer "F.Fab")
		)
		(fp_line
			(start -0.700024 1.500124)
			(end 0.700024 1.500124)
			(stroke
				(width 0.1)
				(type default)
			)
			(layer "F.Fab")
		)
		(fp_rect
			(start -0.700024 1.500124)
			(end 0.700024 -1.500124)
			(stroke
				(width 0)
				(type default)
			)
			(fill no)
			(layer "F.Fab")
		)
		(pad "D" smd rect
			(at 0.999998 0)
			(size 0.8128 0.9144)
			(layers "F.Cu" "F.Mask" "F.Paste")
			(net "PVDDCR_SOC_P1_EN//ADDR_CFG")
		)
		(pad "G" smd rect
			(at -0.999998 -0.94996)
			(size 0.8128 0.9144)
			(layers "F.Cu" "F.Mask" "F.Paste")
			(net "PVDDCR_SOC_P1_EN_GD")
		)
		(pad "S" smd rect
			(at -0.999998 0.94996)
			(size 0.8128 0.9144)
			(layers "F.Cu" "F.Mask" "F.Paste")
			(net "P3V3_AUX")
		)
	)
	(footprint ""
		(layer "F.Cu")
		(at 300.3804 -363.982)
		(property "Reference" "C5004"
			(at 0 0 0)
			(layer "F.SilkS")
			(hide yes)
			(effects
				(font
					(size 1.27 1.27)
				)
			)
		)
		(property "Value" ""
			(at 0 0 0)
			(layer "F.Fab")
			(effects
				(font
					(size 1.27 1.27)
				)
			)
		)
		(duplicate_pad_numbers_are_jumpers no)
		(fp_line
			(start -0.7874 -0.4064)
			(end 0.7874 -0.4064)
			(stroke
				(width 0.1524)
				(type default)
			)
			(layer "F.SilkS")
		)
		(fp_line
			(start -0.7874 0.4064)
			(end -0.7874 -0.4064)
			(stroke
				(width 0.1524)
				(type default)
			)
			(layer "F.SilkS")
		)
		(fp_line
			(start 0.7874 -0.4064)
			(end 0.7874 0.4064)
			(stroke
				(width 0.1524)
				(type default)
			)
			(layer "F.SilkS")
		)
		(fp_line
			(start 0.7874 0.4064)
			(end -0.7874 0.4064)
			(stroke
				(width 0.1524)
				(type default)
			)
			(layer "F.SilkS")
		)
		(fp_line
			(start -0.67945 -0.305054)
			(end -0.12065 -0.305054)
			(stroke
				(width 0.1)
				(type default)
			)
			(layer "F.Fab")
		)
		(fp_line
			(start -0.67945 0.3048)
			(end -0.67945 -0.305054)
			(stroke
				(width 0.1)
				(type default)
			)
			(layer "F.Fab")
		)
		(fp_line
			(start -0.12065 -0.305054)
			(end -0.12065 -0.2794)
			(stroke
				(width 0.1)
				(type default)
			)
			(layer "F.Fab")
		)
		(fp_line
			(start -0.12065 -0.2794)
			(end 0.12065 -0.2794)
			(stroke
				(width 0.1)
				(type default)
			)
			(layer "F.Fab")
		)
		(fp_line
			(start -0.12065 0.2794)
			(end -0.12065 0.3048)
			(stroke
				(width 0.1)
				(type default)
			)
			(layer "F.Fab")
		)
		(fp_line
			(start -0.12065 0.3048)
			(end -0.67945 0.3048)
			(stroke
				(width 0.1)
				(type default)
			)
			(layer "F.Fab")
		)
		(fp_line
			(start 0.120396 0.2794)
			(end -0.12065 0.2794)
			(stroke
				(width 0.1)
				(type default)
			)
			(layer "F.Fab")
		)
		(fp_line
			(start 0.120396 0.3048)
			(end 0.120396 0.2794)
			(stroke
				(width 0.1)
				(type default)
			)
			(layer "F.Fab")
		)
		(fp_line
			(start 0.12065 -0.3048)
			(end 0.67945 -0.3048)
			(stroke
				(width 0.1)
				(type default)
			)
			(layer "F.Fab")
		)
		(fp_line
			(start 0.12065 -0.2794)
			(end 0.12065 -0.3048)
			(stroke
				(width 0.1)
				(type default)
			)
			(layer "F.Fab")
		)
		(fp_line
			(start 0.67945 -0.3048)
			(end 0.67945 0.3048)
			(stroke
				(width 0.1)
				(type default)
			)
			(layer "F.Fab")
		)
		(fp_line
			(start 0.67945 0.3048)
			(end 0.120396 0.3048)
			(stroke
				(width 0.1)
				(type default)
			)
			(layer "F.Fab")
		)
		(pad "1" smd circle
			(at -0.40005 0)
			(size 0 0)
			(layers "F.Cu" "F.Mask" "F.Paste")
			(net "GND")
		)
		(pad "2" smd circle
			(at 0.40005 0)
			(size 0 0)
			(layers "F.Cu" "F.Mask" "F.Paste")
			(net "PWRGD_PVDDCR_CPU1_P0")
		)
	)
)
